# 13919-SA_Riser Card_equal length_1120_1.xlsx — other (si-constraints)
| NET | L1 | Length match <5 mil |
| SATA2_RX_C_DN0 | 614.52 | OK |
| SATA2_RX_C_DP0 | 614 |  |
| SATA2_TX_C_DN0 | 819.86 | OK |
| SATA2_TX_C_DP0 | 820.35 |  |
| USB_P1_DN | 922.32 | OK |
| USB_P1_DP | 921.55 |  |
| CLK_100M_PCIE_SAS_C_N | 760.64 | OK |
| CLK_100M_PCIE_SAS_C_P | 759.8 |  |
| CPU_GBE_RX_C_DN0 | 614.29 | OK |
| CPU_GBE_RX_C_DP0 | 614 |  |
| CPU_GBE_TX_C_DN0 | 801.77 | OK |
| CPU_GBE_TX_C_DP0 | 801.78 |  |
| CLK_100M_CLKBUFF_ENET_DN | 825.73 | OK |
| CLK_100M_CLKBUFF_ENET_DP | 826.24 |  |
